(kicad_pcb
	(version 20260206)
	(generator "pcbnew")
	(generator_version "10.0")
	(general
		(thickness 1.6)
		(legacy_teardrops no)
	)
	(paper "A4")
	(title_block
		(title "v2-pdb — ms_pdb_v2.brd")
		(comment 1 "Open CloudServer (Microsoft) / footprints 42-47 of 348")
	)
	(layers
		(0 "F.Cu" signal "TOP")
		(4 "In1.Cu" signal "GND")
		(6 "In2.Cu" signal "IN1")
		(8 "In3.Cu" signal "VCC")
		(10 "In4.Cu" signal "VCC1")
		(12 "In5.Cu" signal "IN2")
		(14 "In6.Cu" signal "GND1")
		(2 "B.Cu" signal "BOTTOM")
		(9 "F.Adhes" user "F.Adhesive")
		(11 "B.Adhes" user "B.Adhesive")
		(13 "F.Paste" user "Package Geometry/Pastemask Top")
		(15 "B.Paste" user "Package Geometry/Pastemask Bottom")
		(5 "F.SilkS" user "Ref Des/Silkscreen Top")
		(7 "B.SilkS" user "Ref Des/Silkscreen Bottom")
		(1 "F.Mask" user "Board Geometry/Soldermask Top")
		(3 "B.Mask" user "Board Geometry/Soldermask Bottom")
		(17 "Dwgs.User" user "User.Drawings")
		(19 "Cmts.User" user "User.Comments")
		(21 "Eco1.User" user "User.Eco1")
		(23 "Eco2.User" user "User.Eco2")
		(25 "Edge.Cuts" user "Board Geometry/Outline")
		(27 "Margin" user)
		(31 "F.CrtYd" user "Package Geometry/Place Bound Top")
		(29 "B.CrtYd" user "Package Geometry/Place Bound Bottom")
		(35 "F.Fab" user "Ref Des/Assembly Top")
		(33 "B.Fab" user "Ref Des/Assembly Bottom")
	)
	(footprint ""
		(layer "F.Cu")
		(at 5.780024 -477.17202)
		(property "Reference" "J30"
			(at -1.9304 -3.978148 0)
			(unlocked yes)
			(layer "F.SilkS")
			(effects
				(font
					(size 0.7874 0.5842)
					(thickness 0.1524)
				)
				(justify left)
			)
		)
		(property "Value" ""
			(at 0 0 0)
			(layer "F.Fab")
			(effects
				(font
					(size 1.27 1.27)
				)
			)
		)
		(duplicate_pad_numbers_are_jumpers no)
		(fp_line
			(start -3.10007 0.199898)
			(end -3.10007 2.800096)
			(stroke
				(width 0.1524)
				(type default)
			)
			(layer "F.SilkS")
		)
		(fp_line
			(start -3.10007 2.800096)
			(end -1.89992 2.800096)
			(stroke
				(width 0.1524)
				(type default)
			)
			(layer "F.SilkS")
		)
		(fp_line
			(start -1.89992 -3.325114)
			(end -1.89992 0.199898)
			(stroke
				(width 0.1524)
				(type default)
			)
			(layer "F.SilkS")
		)
		(fp_line
			(start -1.89992 0.199898)
			(end -3.10007 0.199898)
			(stroke
				(width 0.1524)
				(type default)
			)
			(layer "F.SilkS")
		)
		(fp_line
			(start -1.89992 2.800096)
			(end -1.89992 6.325108)
			(stroke
				(width 0.1524)
				(type default)
			)
			(layer "F.SilkS")
		)
		(fp_line
			(start -1.89992 6.325108)
			(end 1.016 6.325108)
			(stroke
				(width 0.1524)
				(type default)
			)
			(layer "F.SilkS")
		)
		(fp_line
			(start 1.016 -3.325114)
			(end -1.89992 -3.325114)
			(stroke
				(width 0.1524)
				(type default)
			)
			(layer "F.SilkS")
		)
		(fp_line
			(start 2.469896 5.133594)
			(end 2.469896 -2.130806)
			(stroke
				(width 0.1524)
				(type default)
			)
			(layer "F.SilkS")
		)
		(fp_poly
			(pts
				(xy 0.8509 0.8509) (xy -0.8509 0.8509) (xy -0.8509 -0.8509) (xy 0.8509 -0.8509)
			)
			(stroke
				(width 0)
				(type default)
			)
			(fill no)
			(layer "B.CrtYd")
		)
		(fp_poly
			(pts
				(arc
					(start 0.8509 2.999994)
					(mid -0.8509 2.999994)
					(end 0.8509 2.999994)
				)
			)
			(stroke
				(width 0)
				(type default)
			)
			(fill no)
			(layer "B.CrtYd")
		)
		(fp_poly
			(pts
				(arc
					(start 2.874518 -2.999994)
					(mid 1.045718 -2.999994)
					(end 2.874518 -2.999994)
				)
			)
			(stroke
				(width 0)
				(type default)
			)
			(fill no)
			(layer "B.CrtYd")
		)
		(fp_poly
			(pts
				(arc
					(start 2.874518 5.999988)
					(mid 1.045718 5.999988)
					(end 2.874518 5.999988)
				)
			)
			(stroke
				(width 0)
				(type default)
			)
			(fill no)
			(layer "B.CrtYd")
		)
		(fp_poly
			(pts
				(xy 2.469896 5.233924) (xy 2.469896 -2.233676) (xy 2.8956 -2.233676) (xy 2.8956 -3.935476) (xy 1.0922 -3.935476)
				(xy 1.0922 -3.325114) (xy -1.89992 -3.325114) (xy -1.89992 0.199898) (xy -3.10007 0.199898) (xy -3.10007 2.800096)
				(xy -1.89992 2.800096) (xy -1.89992 6.325108) (xy 1.0922 6.325108) (xy 1.0922 6.935724) (xy 2.8956 6.935724)
				(xy 2.8956 5.233924)
			)
			(stroke
				(width 0)
				(type default)
			)
			(fill no)
			(layer "F.CrtYd")
		)
		(fp_line
			(start -3.10007 0.199898)
			(end -3.10007 2.800096)
			(stroke
				(width 0.1)
				(type default)
			)
			(layer "F.Fab")
		)
		(fp_line
			(start -3.10007 2.800096)
			(end -1.89992 2.800096)
			(stroke
				(width 0.1)
				(type default)
			)
			(layer "F.Fab")
		)
		(fp_line
			(start -1.89992 -3.325114)
			(end -1.89992 0.199898)
			(stroke
				(width 0.1)
				(type default)
			)
			(layer "F.Fab")
		)
		(fp_line
			(start -1.89992 0.199898)
			(end -3.10007 0.199898)
			(stroke
				(width 0.1)
				(type default)
			)
			(layer "F.Fab")
		)
		(fp_line
			(start -1.89992 2.800096)
			(end -1.89992 6.325108)
			(stroke
				(width 0.1)
				(type default)
			)
			(layer "F.Fab")
		)
		(fp_line
			(start -1.89992 6.325108)
			(end 2.469896 6.325108)
			(stroke
				(width 0.1)
				(type default)
			)
			(layer "F.Fab")
		)
		(fp_line
			(start 2.469896 -3.325114)
			(end -1.89992 -3.325114)
			(stroke
				(width 0.1)
				(type default)
			)
			(layer "F.Fab")
		)
		(fp_line
			(start 2.469896 6.325108)
			(end 2.469896 -3.325114)
			(stroke
				(width 0.1)
				(type default)
			)
			(layer "F.Fab")
		)
		(pad "" np_thru_hole circle
			(at 1.960118 -2.999994 90)
			(size 1.3208 1.3208)
			(drill 1.3208)
			(layers "*.Cu" "*.Mask")
			(clearance 0.381)
			(thermal_gap 0.381)
		)
		(pad "" np_thru_hole circle
			(at 1.960118 5.999988 90)
			(size 1.3208 1.3208)
			(drill 1.3208)
			(layers "*.Cu" "*.Mask")
			(clearance 0.381)
			(thermal_gap 0.381)
		)
		(pad "1" thru_hole rect
			(at 0 0 90)
			(size 1.6002 1.6002)
			(drill 1.0922)
			(layers "*.Cu" "*.Mask")
			(remove_unused_layers no)
			(net "POWER_SW3_PWR_CTR_12V")
			(clearance 0)
			(padstack
				(mode front_inner_back)
				(layer "Inner"
					(shape circle)
					(size 1.6002 1.6002)
					(clearance 0)
				)
				(layer "B.Cu"
					(shape rect)
					(size 1.6002 1.6002)
					(clearance 0)
				)
			)
		)
		(pad "2" thru_hole circle
			(at 0 2.999994 90)
			(size 1.6002 1.6002)
			(drill 1.0922)
			(layers "*.Cu" "*.Mask")
			(remove_unused_layers no)
			(net "GND")
			(clearance 0)
		)
		(zone
			(layers "F.Cu" "B.Cu" "In1.Cu" "In2.Cu" "In3.Cu" "In4.Cu" "In5.Cu" "In6.Cu")
			(hatch none 0.5)
			(connect_pads
				(clearance 0)
			)
			(min_thickness 0.25)
			(keepout
				(tracks not_allowed)
				(vias allowed)
				(pads allowed)
				(copperpour not_allowed)
				(footprints allowed)
			)
			(placement
				(enabled no)
				(sheetname "")
			)
			(fill
				(thermal_gap 0.5)
				(thermal_bridge_width 0.5)
				(island_removal_mode 0)
			)
			(polygon
				(pts
					(arc
						(start 8.806942 -480.172014)
						(mid 6.673342 -480.172014)
						(end 8.806942 -480.172014)
					)
				)
			)
		)
		(zone
			(layers "F.Cu" "B.Cu" "In1.Cu" "In2.Cu" "In3.Cu" "In4.Cu" "In5.Cu" "In6.Cu")
			(hatch none 0.5)
			(connect_pads
				(clearance 0)
			)
			(min_thickness 0.25)
			(keepout
				(tracks not_allowed)
				(vias allowed)
				(pads allowed)
				(copperpour not_allowed)
				(footprints allowed)
			)
			(placement
				(enabled no)
				(sheetname "")
			)
			(fill
				(thermal_gap 0.5)
				(thermal_bridge_width 0.5)
				(island_removal_mode 0)
			)
			(polygon
				(pts
					(arc
						(start 8.806942 -471.172032)
						(mid 6.673342 -471.172032)
						(end 8.806942 -471.172032)
					)
				)
			)
		)
	)
	(footprint ""
		(layer "F.Cu")
		(at 16.599916 -384.79984)
		(property "Reference" "H6"
			(at -6.4516 -7.127748 0)
			(unlocked yes)
			(layer "F.SilkS")
			(effects
				(font
					(size 0.7874 0.5842)
					(thickness 0.1524)
				)
				(justify left)
			)
		)
		(property "Value" ""
			(at 0 0 0)
			(layer "F.Fab")
			(effects
				(font
					(size 1.27 1.27)
				)
			)
		)
		(duplicate_pad_numbers_are_jumpers no)
		(fp_circle
			(center 0 0)
			(end 7.999984 0)
			(stroke
				(width 0.1524)
				(type default)
			)
			(fill no)
			(layer "F.SilkS")
		)
		(fp_circle
			(center 0 0)
			(end 14.7066 0)
			(stroke
				(width 0.1524)
				(type default)
			)
			(fill no)
			(layer "B.SilkS")
		)
		(fp_poly
			(pts
				(arc
					(start 0 5.0038)
					(mid 0 -5.0038)
					(end 0 5.0038)
				)
			)
			(stroke
				(width 0)
				(type default)
			)
			(fill no)
			(layer "F.CrtYd")
		)
		(pad "" np_thru_hole circle
			(at 0 0)
			(size 4.0132 4.0132)
			(drill 4.0132)
			(layers "*.Cu" "*.Mask")
			(clearance 0.381)
			(thermal_gap 0.381)
		)
		(pad "2" thru_hole circle
			(at 0 -3.50012)
			(size 0.762 0.762)
			(drill 0.5588)
			(layers "*.Cu" "*.Mask")
			(remove_unused_layers no)
			(net "GND")
			(clearance 0.1524)
			(thermal_gap 0.1524)
		)
		(pad "3" thru_hole circle
			(at -2.500122 -2.500122)
			(size 0.762 0.762)
			(drill 0.5588)
			(layers "*.Cu" "*.Mask")
			(remove_unused_layers no)
			(net "GND")
			(clearance 0.1524)
			(thermal_gap 0.1524)
		)
		(pad "4" thru_hole circle
			(at -3.50012 0)
			(size 0.762 0.762)
			(drill 0.5588)
			(layers "*.Cu" "*.Mask")
			(remove_unused_layers no)
			(net "GND")
			(clearance 0.1524)
			(thermal_gap 0.1524)
		)
		(pad "5" thru_hole circle
			(at -2.500122 2.500122)
			(size 0.762 0.762)
			(drill 0.5588)
			(layers "*.Cu" "*.Mask")
			(remove_unused_layers no)
			(net "GND")
			(clearance 0.1524)
			(thermal_gap 0.1524)
		)
		(pad "6" thru_hole circle
			(at 0 3.50012)
			(size 0.762 0.762)
			(drill 0.5588)
			(layers "*.Cu" "*.Mask")
			(remove_unused_layers no)
			(net "GND")
			(clearance 0.1524)
			(thermal_gap 0.1524)
		)
		(pad "7" thru_hole circle
			(at 2.500122 2.500122)
			(size 0.762 0.762)
			(drill 0.5588)
			(layers "*.Cu" "*.Mask")
			(remove_unused_layers no)
			(net "GND")
			(clearance 0.1524)
			(thermal_gap 0.1524)
		)
		(pad "8" thru_hole circle
			(at 3.50012 0)
			(size 0.762 0.762)
			(drill 0.5588)
			(layers "*.Cu" "*.Mask")
			(remove_unused_layers no)
			(net "GND")
			(clearance 0.1524)
			(thermal_gap 0.1524)
		)
		(pad "9" thru_hole circle
			(at 2.500122 -2.500122)
			(size 0.762 0.762)
			(drill 0.5588)
			(layers "*.Cu" "*.Mask")
			(remove_unused_layers no)
			(net "GND")
			(clearance 0.1524)
			(thermal_gap 0.1524)
		)
		(zone
			(layer "F.Cu")
			(hatch none 0.5)
			(connect_pads
				(clearance 0)
			)
			(min_thickness 0.25)
			(keepout
				(tracks not_allowed)
				(vias allowed)
				(pads allowed)
				(copperpour not_allowed)
				(footprints allowed)
			)
			(placement
				(enabled no)
				(sheetname "")
			)
			(fill
				(thermal_gap 0.5)
				(thermal_bridge_width 0.5)
				(island_removal_mode 0)
			)
			(polygon
				(pts
					(arc
						(start 16.599916 -392.80084)
						(mid 8.598916 -384.79984)
						(end 16.599916 -376.79884)
					)
					(arc
						(start 16.599916 -376.79884)
						(mid 18.035016 -378.23394)
						(end 16.599916 -379.66904)
					)
					(arc
						(start 16.599916 -379.66904)
						(mid 11.469116 -384.79984)
						(end 16.599916 -389.93064)
					)
					(arc
						(start 16.599916 -389.93064)
						(mid 18.035016 -391.36574)
						(end 16.599916 -392.80084)
					)
				)
			)
		)
		(zone
			(layer "F.Cu")
			(hatch none 0.5)
			(connect_pads
				(clearance 0)
			)
			(min_thickness 0.25)
			(keepout
				(tracks not_allowed)
				(vias allowed)
				(pads allowed)
				(copperpour not_allowed)
				(footprints allowed)
			)
			(placement
				(enabled no)
				(sheetname "")
			)
			(fill
				(thermal_gap 0.5)
				(thermal_bridge_width 0.5)
				(island_removal_mode 0)
			)
			(polygon
				(pts
					(arc
						(start 16.599916 -392.80084)
						(mid 24.600916 -384.79984)
						(end 16.599916 -376.79884)
					)
					(arc
						(start 16.599916 -376.79884)
						(mid 15.164816 -378.23394)
						(end 16.599916 -379.66904)
					)
					(arc
						(start 16.599916 -379.66904)
						(mid 21.730716 -384.79984)
						(end 16.599916 -389.93064)
					)
					(arc
						(start 16.599916 -389.93064)
						(mid 15.164816 -391.36574)
						(end 16.599916 -392.80084)
					)
				)
			)
		)
		(zone
			(layers "F.Cu" "B.Cu" "In1.Cu" "In2.Cu" "In3.Cu" "In4.Cu" "In5.Cu" "In6.Cu")
			(hatch none 0.5)
			(connect_pads
				(clearance 0)
			)
			(min_thickness 0.25)
			(keepout
				(tracks not_allowed)
				(vias allowed)
				(pads allowed)
				(copperpour not_allowed)
				(footprints allowed)
			)
			(placement
				(enabled no)
				(sheetname "")
			)
			(fill
				(thermal_gap 0.5)
				(thermal_bridge_width 0.5)
				(island_removal_mode 0)
			)
			(polygon
				(pts
					(arc
						(start 16.599916 -382.28778)
						(mid 16.599916 -387.3119)
						(end 16.599916 -382.28778)
					)
				)
			)
		)
	)
	(footprint ""
		(layer "F.Cu")
		(at 39.436802 -287.17748 90)
		(property "Reference" "R122"
			(at -3.06705 1.662938 90)
			(unlocked yes)
			(layer "F.SilkS")
			(effects
				(font
					(size 0.7874 0.5842)
					(thickness 0.1524)
				)
				(justify left)
			)
		)
		(property "Value" ""
			(at 0 0 90)
			(layer "F.Fab")
			(effects
				(font
					(size 1.27 1.27)
				)
			)
		)
		(duplicate_pad_numbers_are_jumpers no)
		(fp_line
			(start 0.7874 -0.4064)
			(end 0.7874 0.4064)
			(stroke
				(width 0.1524)
				(type default)
			)
			(layer "F.SilkS")
		)
		(fp_line
			(start -0.7874 -0.4064)
			(end 0.7874 -0.4064)
			(stroke
				(width 0.1524)
				(type default)
			)
			(layer "F.SilkS")
		)
		(fp_line
			(start 0.7874 0.4064)
			(end -0.7874 0.4064)
			(stroke
				(width 0.1524)
				(type default)
			)
			(layer "F.SilkS")
		)
		(fp_line
			(start -0.7874 0.4064)
			(end -0.7874 -0.4064)
			(stroke
				(width 0.1524)
				(type default)
			)
			(layer "F.SilkS")
		)
		(fp_poly
			(pts
				(xy -0.508 0.2794) (xy -0.508 0.2286) (xy -0.635 0.2286) (xy -0.635 -0.254) (xy -0.5334 -0.254)
				(xy -0.5334 -0.2794) (xy 0.5334 -0.2794) (xy 0.5334 -0.254) (xy 0.635 -0.254) (xy 0.635 0.254) (xy 0.5334 0.254)
				(xy 0.5334 0.2794)
			)
			(stroke
				(width 0)
				(type default)
			)
			(fill no)
			(layer "F.CrtYd")
		)
		(pad "1" smd rect
			(at 0.40005 0 90)
			(size 0.4572 0.508)
			(layers "F.Cu" "F.Mask" "F.Paste")
			(net "PSU4_REMOTE_P")
		)
		(pad "2" smd rect
			(at -0.40005 0 90)
			(size 0.4572 0.508)
			(layers "F.Cu" "F.Mask" "F.Paste")
			(net "PSU4_REMOTE_R2_P")
		)
	)
	(footprint ""
		(layer "F.Cu")
		(at 25.931622 -100.590096)
		(property "Reference" "R67"
			(at -4.080256 -0.075692 0)
			(unlocked yes)
			(layer "F.SilkS")
			(effects
				(font
					(size 0.7874 0.5842)
					(thickness 0.1524)
				)
				(justify left)
			)
		)
		(property "Value" ""
			(at 0 0 0)
			(layer "F.Fab")
			(effects
				(font
					(size 1.27 1.27)
				)
			)
		)
		(duplicate_pad_numbers_are_jumpers no)
		(fp_line
			(start -0.7874 -0.4064)
			(end 0.7874 -0.4064)
			(stroke
				(width 0.1524)
				(type default)
			)
			(layer "F.SilkS")
		)
		(fp_line
			(start -0.7874 0.4064)
			(end -0.7874 -0.4064)
			(stroke
				(width 0.1524)
				(type default)
			)
			(layer "F.SilkS")
		)
		(fp_line
			(start 0.7874 -0.4064)
			(end 0.7874 0.4064)
			(stroke
				(width 0.1524)
				(type default)
			)
			(layer "F.SilkS")
		)
		(fp_line
			(start 0.7874 0.4064)
			(end -0.7874 0.4064)
			(stroke
				(width 0.1524)
				(type default)
			)
			(layer "F.SilkS")
		)
		(fp_poly
			(pts
				(xy -0.508 0.2794) (xy -0.508 0.2286) (xy -0.635 0.2286) (xy -0.635 -0.254) (xy -0.5334 -0.254)
				(xy -0.5334 -0.2794) (xy 0.5334 -0.2794) (xy 0.5334 -0.254) (xy 0.635 -0.254) (xy 0.635 0.254) (xy 0.5334 0.254)
				(xy 0.5334 0.2794)
			)
			(stroke
				(width 0)
				(type default)
			)
			(fill no)
			(layer "F.CrtYd")
		)
		(pad "1" smd rect
			(at 0.40005 0)
			(size 0.4572 0.508)
			(layers "F.Cu" "F.Mask" "F.Paste")
			(net "PSU2_PS_KILL")
		)
		(pad "2" smd rect
			(at -0.40005 0)
			(size 0.4572 0.508)
			(layers "F.Cu" "F.Mask" "F.Paste")
			(net "GND")
		)
	)
	(footprint ""
		(layer "F.Cu")
		(at 21.471382 -177.804572 90)
		(property "Reference" "R159"
			(at -1.067054 -4.480814 90)
			(unlocked yes)
			(layer "F.SilkS")
			(effects
				(font
					(size 0.7874 0.5842)
					(thickness 0.1524)
				)
				(justify left)
			)
		)
		(property "Value" ""
			(at 0 0 90)
			(layer "F.Fab")
			(effects
				(font
					(size 1.27 1.27)
				)
			)
		)
		(duplicate_pad_numbers_are_jumpers no)
		(fp_line
			(start 0.7874 -0.4064)
			(end 0.7874 0.4064)
			(stroke
				(width 0.1524)
				(type default)
			)
			(layer "F.SilkS")
		)
		(fp_line
			(start -0.7874 -0.4064)
			(end 0.7874 -0.4064)
			(stroke
				(width 0.1524)
				(type default)
			)
			(layer "F.SilkS")
		)
		(fp_line
			(start 0.7874 0.4064)
			(end -0.7874 0.4064)
			(stroke
				(width 0.1524)
				(type default)
			)
			(layer "F.SilkS")
		)
		(fp_line
			(start -0.7874 0.4064)
			(end -0.7874 -0.4064)
			(stroke
				(width 0.1524)
				(type default)
			)
			(layer "F.SilkS")
		)
		(fp_poly
			(pts
				(xy -0.508 0.2794) (xy -0.508 0.2286) (xy -0.635 0.2286) (xy -0.635 -0.254) (xy -0.5334 -0.254)
				(xy -0.5334 -0.2794) (xy 0.5334 -0.2794) (xy 0.5334 -0.254) (xy 0.635 -0.254) (xy 0.635 0.254) (xy 0.5334 0.254)
				(xy 0.5334 0.2794)
			)
			(stroke
				(width 0)
				(type default)
			)
			(fill no)
			(layer "F.CrtYd")
		)
		(pad "1" smd rect
			(at 0.40005 0 90)
			(size 0.4572 0.508)
			(layers "F.Cu" "F.Mask" "F.Paste")
			(net "N42263600")
		)
		(pad "2" smd rect
			(at -0.40005 0 90)
			(size 0.4572 0.508)
			(layers "F.Cu" "F.Mask" "F.Paste")
			(net "N42264085")
		)
	)
	(footprint ""
		(layer "F.Cu")
		(at 27.28468 -4.025138)
		(property "Reference" "R65"
			(at -1.676146 2.569972 0)
			(unlocked yes)
			(layer "F.SilkS")
			(effects
				(font
					(size 0.7874 0.5842)
					(thickness 0.1524)
				)
				(justify left)
			)
		)
		(property "Value" ""
			(at 0 0 0)
			(layer "F.Fab")
			(effects
				(font
					(size 1.27 1.27)
				)
			)
		)
		(duplicate_pad_numbers_are_jumpers no)
		(fp_line
			(start -0.7874 -0.4064)
			(end 0.7874 -0.4064)
			(stroke
				(width 0.1524)
				(type default)
			)
			(layer "F.SilkS")
		)
		(fp_line
			(start -0.7874 0.4064)
			(end -0.7874 -0.4064)
			(stroke
				(width 0.1524)
				(type default)
			)
			(layer "F.SilkS")
		)
		(fp_line
			(start 0.7874 -0.4064)
			(end 0.7874 0.4064)
			(stroke
				(width 0.1524)
				(type default)
			)
			(layer "F.SilkS")
		)
		(fp_line
			(start 0.7874 0.4064)
			(end -0.7874 0.4064)
			(stroke
				(width 0.1524)
				(type default)
			)
			(layer "F.SilkS")
		)
		(fp_poly
			(pts
				(xy -0.508 0.2794) (xy -0.508 0.2286) (xy -0.635 0.2286) (xy -0.635 -0.254) (xy -0.5334 -0.254)
				(xy -0.5334 -0.2794) (xy 0.5334 -0.2794) (xy 0.5334 -0.254) (xy 0.635 -0.254) (xy 0.635 0.254) (xy 0.5334 0.254)
				(xy 0.5334 0.2794)
			)
			(stroke
				(width 0)
				(type default)
			)
			(fill no)
			(layer "F.CrtYd")
		)
		(pad "1" smd rect
			(at 0.40005 0)
			(size 0.4572 0.508)
			(layers "F.Cu" "F.Mask" "F.Paste")
			(net "PSU1_RESET")
		)
		(pad "2" smd rect
			(at -0.40005 0)
			(size 0.4572 0.508)
			(layers "F.Cu" "F.Mask" "F.Paste")
			(net "GND")
		)
	)
)
